# S9S_MB_2U (Grand Teton) — schematic netlist excerpt (pin names and nets, part order shuffled) for the footprints in the layout excerpt that follows; sources: Cadence DE-HDL packaged netlist, KiCad conversion of 03242023_DA0F0TMBIJ0_F0T_Motherboard_J_brd_V01_OCP.brd

C1768  Q_CAP  10UF 16V 10% EMPTY  pkg C0805  page 250 : A = P3V3_MAX11617_VDD ; B = GND
PC2087  Q_CAP  1UF 25V 10% EMPTY  pkg C0402  page 156 : A = GND ; B = P12V_OCP_REG_1
PR1305  Q_RES  8.87K 1% EMPTY  pkg 0402LF  page 290 : A = PVCCFA_EHV_FIVRA_CPU1_LSET3 ; B = GND

(kicad_pcb
	(version 20260206)
	(generator "pcbnew")
	(generator_version "10.0")
	(general
		(thickness 1.6)
		(legacy_teardrops no)
	)
	(paper "A4")
	(title_block
		(title "03242023_DA0F0TMBIJ0_F0T_Motherboard_J_brd_V01_OCP.brd")
		(comment 1 "Grand Teton / footprints 3246-3248 of 6105")
	)
	(layers
		(0 "F.Cu" signal "TOP")
		(4 "In1.Cu" signal "GND")
		(6 "In2.Cu" signal "IN1")
		(8 "In3.Cu" signal "GND1")
		(10 "In4.Cu" signal "IN2")
		(12 "In5.Cu" signal "GND2")
		(14 "In6.Cu" signal "IN3")
		(16 "In7.Cu" signal "GND3")
		(18 "In8.Cu" signal "VCC")
		(20 "In9.Cu" signal "VCC1")
		(22 "In10.Cu" signal "GND4")
		(24 "In11.Cu" signal "IN4")
		(26 "In12.Cu" signal "GND5")
		(28 "In13.Cu" signal "IN5")
		(30 "In14.Cu" signal "GND6")
		(32 "In15.Cu" signal "IN6")
		(34 "In16.Cu" signal "GND7")
		(2 "B.Cu" signal "BOTTOM")
		(9 "F.Adhes" user "F.Adhesive")
		(11 "B.Adhes" user "B.Adhesive")
		(13 "F.Paste" user "Package Geometry/Pastemask Top")
		(15 "B.Paste" user "Package Geometry/Pastemask Bottom")
		(5 "F.SilkS" user "Ref Des/Silkscreen Top")
		(7 "B.SilkS" user "Ref Des/Silkscreen Bottom")
		(1 "F.Mask" user "Board Geometry/Soldermask Top")
		(3 "B.Mask" user "Board Geometry/Soldermask Bottom")
		(17 "Dwgs.User" user "User.Drawings")
		(19 "Cmts.User" user "User.Comments")
		(21 "Eco1.User" user "User.Eco1")
		(23 "Eco2.User" user "User.Eco2")
		(25 "Edge.Cuts" user "Board Geometry/Outline")
		(27 "Margin" user)
		(31 "F.CrtYd" user "Package Geometry/Place Bound Top")
		(29 "B.CrtYd" user "Package Geometry/Place Bound Bottom")
		(35 "F.Fab" user "Ref Des/Assembly Top")
		(33 "B.Fab" user "Ref Des/Assembly Bottom")
	)
	(footprint ""
		(layer "F.Cu")
		(at 46.828964 -104.279446)
		(property "Reference" "C1768"
			(at 0 0 0)
			(layer "F.SilkS")
			(hide yes)
			(effects
				(font
					(size 1.27 1.27)
				)
			)
		)
		(property "Value" ""
			(at 0 0 0)
			(layer "F.Fab")
			(effects
				(font
					(size 1.27 1.27)
				)
			)
		)
		(duplicate_pad_numbers_are_jumpers no)
		(fp_line
			(start -1.524 -0.762)
			(end 1.524 -0.762)
			(stroke
				(width 0.1524)
				(type default)
			)
			(layer "F.SilkS")
		)
		(fp_line
			(start -1.524 0.762)
			(end -1.524 -0.762)
			(stroke
				(width 0.1524)
				(type default)
			)
			(layer "F.SilkS")
		)
		(fp_line
			(start 1.524 -0.762)
			(end 1.524 0.762)
			(stroke
				(width 0.1524)
				(type default)
			)
			(layer "F.SilkS")
		)
		(fp_line
			(start 1.524 0.762)
			(end -1.524 0.762)
			(stroke
				(width 0.1524)
				(type default)
			)
			(layer "F.SilkS")
		)
		(fp_line
			(start -1.1049 -0.724916)
			(end -1.1049 0.724916)
			(stroke
				(width 0.1)
				(type default)
			)
			(layer "F.Fab")
		)
		(fp_line
			(start -1.1049 0.724916)
			(end 1.1049 0.724916)
			(stroke
				(width 0.1)
				(type default)
			)
			(layer "F.Fab")
		)
		(fp_line
			(start 1.1049 -0.724916)
			(end -1.1049 -0.724916)
			(stroke
				(width 0.1)
				(type default)
			)
			(layer "F.Fab")
		)
		(fp_line
			(start 1.1049 0.724916)
			(end 1.1049 -0.724916)
			(stroke
				(width 0.1)
				(type default)
			)
			(layer "F.Fab")
		)
		(pad "1" smd rect
			(at -0.889 0 180)
			(size 1.016 1.27)
			(layers "F.Cu" "F.Mask" "F.Paste")
			(net "P3V3_MAX11617_VDD")
		)
		(pad "2" smd rect
			(at 0.889 0 180)
			(size 1.016 1.27)
			(layers "F.Cu" "F.Mask" "F.Paste")
			(net "GND")
		)
	)
	(footprint ""
		(layer "F.Cu")
		(at 180.42128 -358.698292)
		(property "Reference" "PR1305"
			(at 0 0 0)
			(layer "F.SilkS")
			(hide yes)
			(effects
				(font
					(size 1.27 1.27)
				)
			)
		)
		(property "Value" ""
			(at 0 0 0)
			(layer "F.Fab")
			(effects
				(font
					(size 1.27 1.27)
				)
			)
		)
		(duplicate_pad_numbers_are_jumpers no)
		(fp_line
			(start -0.7874 -0.4064)
			(end 0.7874 -0.4064)
			(stroke
				(width 0.1524)
				(type default)
			)
			(layer "F.SilkS")
		)
		(fp_line
			(start -0.7874 0.4064)
			(end -0.7874 -0.4064)
			(stroke
				(width 0.1524)
				(type default)
			)
			(layer "F.SilkS")
		)
		(fp_line
			(start 0.7874 -0.4064)
			(end 0.7874 0.4064)
			(stroke
				(width 0.1524)
				(type default)
			)
			(layer "F.SilkS")
		)
		(fp_line
			(start 0.7874 0.4064)
			(end -0.7874 0.4064)
			(stroke
				(width 0.1524)
				(type default)
			)
			(layer "F.SilkS")
		)
		(fp_line
			(start -0.67945 -0.305054)
			(end -0.12065 -0.305054)
			(stroke
				(width 0.1)
				(type default)
			)
			(layer "F.Fab")
		)
		(fp_line
			(start -0.67945 0.3048)
			(end -0.67945 -0.305054)
			(stroke
				(width 0.1)
				(type default)
			)
			(layer "F.Fab")
		)
		(fp_line
			(start -0.12065 -0.305054)
			(end -0.12065 -0.2794)
			(stroke
				(width 0.1)
				(type default)
			)
			(layer "F.Fab")
		)
		(fp_line
			(start -0.12065 -0.2794)
			(end 0.12065 -0.2794)
			(stroke
				(width 0.1)
				(type default)
			)
			(layer "F.Fab")
		)
		(fp_line
			(start -0.12065 0.2794)
			(end -0.12065 0.3048)
			(stroke
				(width 0.1)
				(type default)
			)
			(layer "F.Fab")
		)
		(fp_line
			(start -0.12065 0.3048)
			(end -0.67945 0.3048)
			(stroke
				(width 0.1)
				(type default)
			)
			(layer "F.Fab")
		)
		(fp_line
			(start 0.120396 0.2794)
			(end -0.12065 0.2794)
			(stroke
				(width 0.1)
				(type default)
			)
			(layer "F.Fab")
		)
		(fp_line
			(start 0.120396 0.3048)
			(end 0.120396 0.2794)
			(stroke
				(width 0.1)
				(type default)
			)
			(layer "F.Fab")
		)
		(fp_line
			(start 0.12065 -0.3048)
			(end 0.67945 -0.3048)
			(stroke
				(width 0.1)
				(type default)
			)
			(layer "F.Fab")
		)
		(fp_line
			(start 0.12065 -0.2794)
			(end 0.12065 -0.3048)
			(stroke
				(width 0.1)
				(type default)
			)
			(layer "F.Fab")
		)
		(fp_line
			(start 0.67945 -0.3048)
			(end 0.67945 0.3048)
			(stroke
				(width 0.1)
				(type default)
			)
			(layer "F.Fab")
		)
		(fp_line
			(start 0.67945 0.3048)
			(end 0.120396 0.3048)
			(stroke
				(width 0.1)
				(type default)
			)
			(layer "F.Fab")
		)
		(pad "1" smd circle
			(at -0.40005 0)
			(size 0 0)
			(layers "F.Cu" "F.Mask" "F.Paste")
			(net "PVCCFA_EHV_FIVRA_CPU1_LSET3")
		)
		(pad "2" smd circle
			(at 0.40005 0)
			(size 0 0)
			(layers "F.Cu" "F.Mask" "F.Paste")
			(net "GND")
		)
	)
	(footprint ""
		(layer "F.Cu")
		(at 447.565272 -19.506438)
		(property "Reference" "PC2087"
			(at 0 0 0)
			(layer "F.SilkS")
			(hide yes)
			(effects
				(font
					(size 1.27 1.27)
				)
			)
		)
		(property "Value" ""
			(at 0 0 0)
			(layer "F.Fab")
			(effects
				(font
					(size 1.27 1.27)
				)
			)
		)
		(duplicate_pad_numbers_are_jumpers no)
		(fp_line
			(start -0.7874 -0.4064)
			(end 0.7874 -0.4064)
			(stroke
				(width 0.1524)
				(type default)
			)
			(layer "F.SilkS")
		)
		(fp_line
			(start -0.7874 0.4064)
			(end -0.7874 -0.4064)
			(stroke
				(width 0.1524)
				(type default)
			)
			(layer "F.SilkS")
		)
		(fp_line
			(start 0.7874 -0.4064)
			(end 0.7874 0.4064)
			(stroke
				(width 0.1524)
				(type default)
			)
			(layer "F.SilkS")
		)
		(fp_line
			(start 0.7874 0.4064)
			(end -0.7874 0.4064)
			(stroke
				(width 0.1524)
				(type default)
			)
			(layer "F.SilkS")
		)
		(fp_line
			(start -0.67945 -0.305054)
			(end -0.12065 -0.305054)
			(stroke
				(width 0.1)
				(type default)
			)
			(layer "F.Fab")
		)
		(fp_line
			(start -0.67945 0.3048)
			(end -0.67945 -0.305054)
			(stroke
				(width 0.1)
				(type default)
			)
			(layer "F.Fab")
		)
		(fp_line
			(start -0.12065 -0.305054)
			(end -0.12065 -0.2794)
			(stroke
				(width 0.1)
				(type default)
			)
			(layer "F.Fab")
		)
		(fp_line
			(start -0.12065 -0.2794)
			(end 0.12065 -0.2794)
			(stroke
				(width 0.1)
				(type default)
			)
			(layer "F.Fab")
		)
		(fp_line
			(start -0.12065 0.2794)
			(end -0.12065 0.3048)
			(stroke
				(width 0.1)
				(type default)
			)
			(layer "F.Fab")
		)
		(fp_line
			(start -0.12065 0.3048)
			(end -0.67945 0.3048)
			(stroke
				(width 0.1)
				(type default)
			)
			(layer "F.Fab")
		)
		(fp_line
			(start 0.120396 0.2794)
			(end -0.12065 0.2794)
			(stroke
				(width 0.1)
				(type default)
			)
			(layer "F.Fab")
		)
		(fp_line
			(start 0.120396 0.3048)
			(end 0.120396 0.2794)
			(stroke
				(width 0.1)
				(type default)
			)
			(layer "F.Fab")
		)
		(fp_line
			(start 0.12065 -0.3048)
			(end 0.67945 -0.3048)
			(stroke
				(width 0.1)
				(type default)
			)
			(layer "F.Fab")
		)
		(fp_line
			(start 0.12065 -0.2794)
			(end 0.12065 -0.3048)
			(stroke
				(width 0.1)
				(type default)
			)
			(layer "F.Fab")
		)
		(fp_line
			(start 0.67945 -0.3048)
			(end 0.67945 0.3048)
			(stroke
				(width 0.1)
				(type default)
			)
			(layer "F.Fab")
		)
		(fp_line
			(start 0.67945 0.3048)
			(end 0.120396 0.3048)
			(stroke
				(width 0.1)
				(type default)
			)
			(layer "F.Fab")
		)
		(pad "1" smd circle
			(at -0.40005 0)
			(size 0 0)
			(layers "F.Cu" "F.Mask" "F.Paste")
			(net "GND")
		)
		(pad "2" smd circle
			(at 0.40005 0)
			(size 0 0)
			(layers "F.Cu" "F.Mask" "F.Paste")
			(net "P12V_OCP_REG_1")
		)
	)
)
